(kicad_pcb
	(version 20260206)
	(generator "pcbnew")
	(generator_version "10.0")
	(general
		(thickness 1.6)
		(legacy_teardrops no)
	)
	(paper "A4")
	(title_block
		(title "Wiwynn_Tioga_Pass_MB.brd")
		(comment 1 "Tioga Pass / footprint 190 of 4770 (U2D1), pads 193-302 of 3647")
	)
	(layers
		(0 "F.Cu" signal "TOP")
		(4 "In1.Cu" signal "L2GND")
		(6 "In2.Cu" signal "L3")
		(8 "In3.Cu" signal "L4GND")
		(10 "In4.Cu" signal "L5")
		(12 "In5.Cu" signal "L6GND")
		(14 "In6.Cu" signal "L7VCC")
		(16 "In7.Cu" signal "L8VCC")
		(18 "In8.Cu" signal "L9GND")
		(20 "In9.Cu" signal "L10")
		(22 "In10.Cu" signal "L11GND")
		(24 "In11.Cu" signal "L12")
		(26 "In12.Cu" signal "L13GND")
		(2 "B.Cu" signal "BOTTOM")
		(9 "F.Adhes" user "F.Adhesive")
		(11 "B.Adhes" user "B.Adhesive")
		(13 "F.Paste" user "Package Geometry/Pastemask Top")
		(15 "B.Paste" user "Package Geometry/Pastemask Bottom")
		(5 "F.SilkS" user "Ref Des/Silkscreen Top")
		(7 "B.SilkS" user "Ref Des/Silkscreen Bottom")
		(1 "F.Mask" user "Board Geometry/Soldermask Top")
		(3 "B.Mask" user "Board Geometry/Soldermask Bottom")
		(17 "Dwgs.User" user "User.Drawings")
		(19 "Cmts.User" user "User.Comments")
		(21 "Eco1.User" user "User.Eco1")
		(23 "Eco2.User" user "User.Eco2")
		(25 "Edge.Cuts" user "Board Geometry/Outline")
		(27 "Margin" user)
		(31 "F.CrtYd" user "Package Geometry/Place Bound Top")
		(29 "B.CrtYd" user "Package Geometry/Place Bound Bottom")
		(35 "F.Fab" user "Ref Des/Assembly Top")
		(33 "B.Fab" user "Ref Des/Assembly Bottom")
	)
	(footprint ""
		(layer "F.Cu")
		(at 104.99979 -76.550012 180)
		(property "Reference" "U2D1"
			(at 25.19299 30.484318 0)
			(unlocked yes)
			(layer "F.SilkS")
			(effects
				(font
					(size 0.7874 0.5842)
					(thickness 0.1524)
				)
			)
		)
		(property "Value" ""
			(at 0 0 180)
			(layer "F.Fab")
			(effects
				(font
					(size 1.27 1.27)
				)
			)
		)
		(duplicate_pad_numbers_are_jumpers no)
		(pad "AE12" smd circle
			(at -27.806904 -13.215874)
			(size 0.4318 0.4318)
			(layers "F.Cu" "F.Mask" "F.Paste")
			(net "XDP_CPU_OBSFN_B0_MBP6_N")
		)
		(pad "AE14" smd circle
			(at -26.090118 -13.215874)
			(size 0.4318 0.4318)
			(layers "F.Cu" "F.Mask" "F.Paste")
			(net "XDP_CPU1_TDO")
		)
		(pad "AE16" smd circle
			(at -24.373078 -13.215874)
			(size 0.4318 0.4318)
			(layers "F.Cu" "F.Mask" "F.Paste")
			(net "GND")
		)
		(pad "AE18" smd circle
			(at -22.656038 -13.215874)
			(size 0.4318 0.4318)
			(layers "F.Cu" "F.Mask" "F.Paste")
			(net "SMB_DDR_KLM_SCL_G_R")
		)
		(pad "AE20" smd circle
			(at -20.938998 -13.215874)
			(size 0.4318 0.4318)
			(layers "F.Cu" "F.Mask" "F.Paste")
			(net "PU_CPU1_LEGACY_SKT")
		)
		(pad "AE22" smd circle
			(at -19.221958 -13.215874)
			(size 0.4318 0.4318)
			(layers "F.Cu" "F.Mask" "F.Paste")
			(net "M_J_DQ<58>")
		)
		(pad "AE24" smd circle
			(at -17.504918 -13.215874)
			(size 0.4318 0.4318)
			(layers "F.Cu" "F.Mask" "F.Paste")
			(net "M_J_DQS_DP<16>")
		)
		(pad "AE26" smd circle
			(at -15.787878 -13.215874)
			(size 0.4318 0.4318)
			(layers "F.Cu" "F.Mask" "F.Paste")
			(net "M_J_DQ<60>")
		)
		(pad "AE28" smd circle
			(at -14.071092 -13.215874)
			(size 0.4318 0.4318)
			(layers "F.Cu" "F.Mask" "F.Paste")
			(net "M_J_DQ<50>")
		)
		(pad "AE30" smd circle
			(at -12.354052 -13.215874)
			(size 0.4318 0.4318)
			(layers "F.Cu" "F.Mask" "F.Paste")
			(net "M_J_DQS_DP<15>")
		)
		(pad "AE32" smd circle
			(at -10.637012 -13.215874)
			(size 0.4318 0.4318)
			(layers "F.Cu" "F.Mask" "F.Paste")
			(net "M_J_DQ<52>")
		)
		(pad "AE34" smd circle
			(at -8.919972 -13.215874)
			(size 0.4318 0.4318)
			(layers "F.Cu" "F.Mask" "F.Paste")
			(net "PVCCIO_CPU1")
		)
		(pad "AE36" smd circle
			(at -7.202932 -13.215874)
			(size 0.4318 0.4318)
			(layers "F.Cu" "F.Mask" "F.Paste")
			(net "PVCCIO_CPU1")
		)
		(pad "AE38" smd circle
			(at -5.485892 -13.215874)
			(size 0.4318 0.4318)
			(layers "F.Cu" "F.Mask" "F.Paste")
			(net "GND")
		)
		(pad "AE40" smd circle
			(at -3.769106 -13.215874)
			(size 0.4318 0.4318)
			(layers "F.Cu" "F.Mask" "F.Paste")
			(net "GND")
		)
		(pad "AE42" smd circle
			(at -2.052066 -13.215874)
			(size 0.4318 0.4318)
			(layers "F.Cu" "F.Mask" "F.Paste")
			(net "GND")
		)
		(pad "AE46" smd circle
			(at 2.910586 -15.015972)
			(size 0.4318 0.4318)
			(layers "F.Cu" "F.Mask" "F.Paste")
			(net "TP_CPU1_RSVD_251")
		)
		(pad "AE48" smd circle
			(at 4.627626 -15.015972)
			(size 0.4318 0.4318)
			(layers "F.Cu" "F.Mask" "F.Paste")
			(net "TP_CPU1_RSVD_250")
		)
		(pad "AE50" smd circle
			(at 6.344412 -15.015972)
			(size 0.4318 0.4318)
			(layers "F.Cu" "F.Mask" "F.Paste")
			(net "TP_CPU1_RSVD_249")
		)
		(pad "AE52" smd circle
			(at 8.061452 -15.015972)
			(size 0.4318 0.4318)
			(layers "F.Cu" "F.Mask" "F.Paste")
			(net "TP_CPU1_RSVD_248")
		)
		(pad "AE54" smd circle
			(at 9.778492 -15.015972)
			(size 0.4318 0.4318)
			(layers "F.Cu" "F.Mask" "F.Paste")
			(net "M_J_MA<15>")
		)
		(pad "AE56" smd circle
			(at 11.495532 -15.015972)
			(size 0.4318 0.4318)
			(layers "F.Cu" "F.Mask" "F.Paste")
			(net "M_J_BA<1>")
		)
		(pad "AE58" smd circle
			(at 13.212572 -15.015972)
			(size 0.4318 0.4318)
			(layers "F.Cu" "F.Mask" "F.Paste")
			(net "M_J_MA<1>")
		)
		(pad "AE60" smd circle
			(at 14.929612 -15.015972)
			(size 0.4318 0.4318)
			(layers "F.Cu" "F.Mask" "F.Paste")
			(net "M_J_MA<7>")
		)
		(pad "AE62" smd circle
			(at 16.646398 -15.015972)
			(size 0.4318 0.4318)
			(layers "F.Cu" "F.Mask" "F.Paste")
			(net "M_J_BG<1>")
		)
		(pad "AE64" smd circle
			(at 18.363438 -15.015972)
			(size 0.4318 0.4318)
			(layers "F.Cu" "F.Mask" "F.Paste")
			(net "GND")
		)
		(pad "AE66" smd circle
			(at 20.080478 -15.015972)
			(size 0.4318 0.4318)
			(layers "F.Cu" "F.Mask" "F.Paste")
			(net "GND")
		)
		(pad "AE68" smd circle
			(at 21.797518 -15.015972)
			(size 0.4318 0.4318)
			(layers "F.Cu" "F.Mask" "F.Paste")
			(net "GND")
		)
		(pad "AE70" smd circle
			(at 23.514558 -15.015972)
			(size 0.4318 0.4318)
			(layers "F.Cu" "F.Mask" "F.Paste")
			(net "GND")
		)
		(pad "AE72" smd circle
			(at 25.231598 -15.015972)
			(size 0.4318 0.4318)
			(layers "F.Cu" "F.Mask" "F.Paste")
			(net "TP_CPU1_RSVD_247")
		)
		(pad "AE74" smd circle
			(at 26.948384 -15.015972)
			(size 0.4318 0.4318)
			(layers "F.Cu" "F.Mask" "F.Paste")
			(net "M_J_DQ<13>")
		)
		(pad "AE76" smd circle
			(at 28.665424 -15.015972)
			(size 0.4318 0.4318)
			(layers "F.Cu" "F.Mask" "F.Paste")
			(net "M_J_DQ<8>")
		)
		(pad "AE78" smd circle
			(at 30.382464 -15.015972)
			(size 0.4318 0.4318)
			(layers "F.Cu" "F.Mask" "F.Paste")
			(net "GND")
		)
		(pad "AE80" smd circle
			(at 32.099504 -15.015972)
			(size 0.4318 0.4318)
			(layers "F.Cu" "F.Mask" "F.Paste")
			(net "M_H_DQS_DP<1>")
		)
		(pad "AE82" smd circle
			(at 33.816544 -15.015972)
			(size 0.4318 0.4318)
			(layers "F.Cu" "F.Mask" "F.Paste")
			(net "M_H_DQ<14>")
		)
		(pad "AE84" smd circle
			(at 35.533584 -15.015972)
			(size 0.4318 0.4318)
			(layers "F.Cu" "F.Mask" "F.Paste")
			(net "M_G_DQ<3>")
		)
		(pad "AE86" smd custom
			(at 37.250624 -15.015972 270)
			(size 0.10795 0.10795)
			(layers "F.Cu" "F.Mask" "F.Paste")
			(net "M_G_DQ<2>")
			(options
				(clearance outline)
				(anchor circle)
			)
			(primitives
				(gr_poly
					(pts
						(arc
							(start 0.2159 -0.0381)
							(mid 0 -0.254)
							(end -0.2159 -0.0381)
						)
						(arc
							(start -0.2159 0.0381)
							(mid 0 0.254)
							(end 0.2159 0.0381)
						)
					)
					(width 0)
					(fill yes)
				)
			)
		)
		(pad "AF1" smd custom
			(at -37.250624 -12.720828 90)
			(size 0.10795 0.10795)
			(layers "F.Cu" "F.Mask" "F.Paste")
			(net "GND")
			(options
				(clearance outline)
				(anchor circle)
			)
			(primitives
				(gr_poly
					(pts
						(arc
							(start 0.2159 -0.0381)
							(mid 0 -0.254)
							(end -0.2159 -0.0381)
						)
						(arc
							(start -0.2159 0.0381)
							(mid 0 0.254)
							(end 0.2159 0.0381)
						)
					)
					(width 0)
					(fill yes)
				)
			)
		)
		(pad "AF3" smd circle
			(at -35.533584 -12.720828)
			(size 0.4318 0.4318)
			(layers "F.Cu" "F.Mask" "F.Paste")
			(net "UPI_CPU1_CPU0_P0P0_DP<6>")
		)
		(pad "AF5" smd circle
			(at -33.816544 -12.720828)
			(size 0.4318 0.4318)
			(layers "F.Cu" "F.Mask" "F.Paste")
			(net "PVCCIO_CPU1")
		)
		(pad "AF7" smd circle
			(at -32.099504 -12.720828)
			(size 0.4318 0.4318)
			(layers "F.Cu" "F.Mask" "F.Paste")
			(net "UPI_CPU0_CPU1_P0P0_DN<5>")
		)
		(pad "AF9" smd circle
			(at -30.382464 -12.720828)
			(size 0.4318 0.4318)
			(layers "F.Cu" "F.Mask" "F.Paste")
			(net "GND")
		)
		(pad "AF11" smd circle
			(at -28.665424 -12.720828)
			(size 0.4318 0.4318)
			(layers "F.Cu" "F.Mask" "F.Paste")
			(net "TP_XDP_CPU1_OBSDATA_B1_MBP3_N")
		)
		(pad "AF13" smd circle
			(at -26.948384 -12.720828)
			(size 0.4318 0.4318)
			(layers "F.Cu" "F.Mask" "F.Paste")
			(net "H_CPU1_MEMKLM_MEMHOT_G_N")
		)
		(pad "AF15" smd circle
			(at -25.231598 -12.720828)
			(size 0.4318 0.4318)
			(layers "F.Cu" "F.Mask" "F.Paste")
			(net "H_CPU1_FAST_WAKE_N")
		)
		(pad "AF17" smd circle
			(at -23.514558 -12.720828)
			(size 0.4318 0.4318)
			(layers "F.Cu" "F.Mask" "F.Paste")
			(net "SMB_DDR_GHJ_SDA_G_R")
		)
		(pad "AF19" smd circle
			(at -21.797518 -12.720828)
			(size 0.4318 0.4318)
			(layers "F.Cu" "F.Mask" "F.Paste")
			(net "TP_CPU1_RSVD_246")
		)
		(pad "AF21" smd circle
			(at -20.080478 -12.720828)
			(size 0.4318 0.4318)
			(layers "F.Cu" "F.Mask" "F.Paste")
			(net "GND")
		)
		(pad "AF23" smd circle
			(at -18.363438 -12.720828)
			(size 0.4318 0.4318)
			(layers "F.Cu" "F.Mask" "F.Paste")
			(net "GND")
		)
		(pad "AF25" smd circle
			(at -16.646398 -12.720828)
			(size 0.4318 0.4318)
			(layers "F.Cu" "F.Mask" "F.Paste")
			(net "GND")
		)
		(pad "AF27" smd circle
			(at -14.929612 -12.720828)
			(size 0.4318 0.4318)
			(layers "F.Cu" "F.Mask" "F.Paste")
			(net "GND")
		)
		(pad "AF29" smd circle
			(at -13.212572 -12.720828)
			(size 0.4318 0.4318)
			(layers "F.Cu" "F.Mask" "F.Paste")
			(net "GND")
		)
		(pad "AF31" smd circle
			(at -11.495532 -12.720828)
			(size 0.4318 0.4318)
			(layers "F.Cu" "F.Mask" "F.Paste")
			(net "GND")
		)
		(pad "AF33" smd circle
			(at -9.778492 -12.720828)
			(size 0.4318 0.4318)
			(layers "F.Cu" "F.Mask" "F.Paste")
			(net "GND")
		)
		(pad "AF35" smd circle
			(at -8.061452 -12.720828)
			(size 0.4318 0.4318)
			(layers "F.Cu" "F.Mask" "F.Paste")
			(net "PVCCIO_CPU1")
		)
		(pad "AF37" smd circle
			(at -6.344412 -12.720828)
			(size 0.4318 0.4318)
			(layers "F.Cu" "F.Mask" "F.Paste")
			(net "GND")
		)
		(pad "AF39" smd circle
			(at -4.627626 -12.720828)
			(size 0.4318 0.4318)
			(layers "F.Cu" "F.Mask" "F.Paste")
			(net "GND")
		)
		(pad "AF41" smd circle
			(at -2.910586 -12.720828)
			(size 0.4318 0.4318)
			(layers "F.Cu" "F.Mask" "F.Paste")
			(net "GND")
		)
		(pad "AF43" smd circle
			(at -1.193546 -12.720828)
			(size 0.4318 0.4318)
			(layers "F.Cu" "F.Mask" "F.Paste")
			(net "PVCCIN_CPU1")
		)
		(pad "AF45" smd circle
			(at 2.052066 -14.520926)
			(size 0.508 0.508)
			(layers "F.Cu" "F.Mask" "F.Paste")
			(net "PD_CPU1_RSVD_TEST_1")
		)
		(pad "AF47" smd circle
			(at 3.769106 -14.520926)
			(size 0.4318 0.4318)
			(layers "F.Cu" "F.Mask" "F.Paste")
			(net "TP_CPU1_RSVD_245")
		)
		(pad "AF49" smd circle
			(at 5.485892 -14.520926)
			(size 0.4318 0.4318)
			(layers "F.Cu" "F.Mask" "F.Paste")
			(net "TP_CPU1_RSVD_244")
		)
		(pad "AF51" smd circle
			(at 7.202932 -14.520926)
			(size 0.4318 0.4318)
			(layers "F.Cu" "F.Mask" "F.Paste")
			(net "TP_CPU1_RSVD_243")
		)
		(pad "AF53" smd circle
			(at 8.919972 -14.520926)
			(size 0.4318 0.4318)
			(layers "F.Cu" "F.Mask" "F.Paste")
			(net "TP_CPU1_RSVD_242")
		)
		(pad "AF55" smd circle
			(at 10.637012 -14.520926)
			(size 0.4318 0.4318)
			(layers "F.Cu" "F.Mask" "F.Paste")
			(net "PVDDQ_GHJ")
		)
		(pad "AF57" smd circle
			(at 12.354052 -14.520926)
			(size 0.4318 0.4318)
			(layers "F.Cu" "F.Mask" "F.Paste")
			(net "PVDDQ_GHJ")
		)
		(pad "AF59" smd circle
			(at 14.071092 -14.520926)
			(size 0.4318 0.4318)
			(layers "F.Cu" "F.Mask" "F.Paste")
			(net "PVDDQ_GHJ")
		)
		(pad "AF61" smd circle
			(at 15.787878 -14.520926)
			(size 0.4318 0.4318)
			(layers "F.Cu" "F.Mask" "F.Paste")
			(net "PVDDQ_GHJ")
		)
		(pad "AF63" smd circle
			(at 17.504918 -14.520926)
			(size 0.4318 0.4318)
			(layers "F.Cu" "F.Mask" "F.Paste")
			(net "PVDDQ_GHJ")
		)
		(pad "AF65" smd circle
			(at 19.221958 -14.520926)
			(size 0.4318 0.4318)
			(layers "F.Cu" "F.Mask" "F.Paste")
			(net "M_G_ECC<3>")
		)
		(pad "AF67" smd circle
			(at 20.938998 -14.520926)
			(size 0.4318 0.4318)
			(layers "F.Cu" "F.Mask" "F.Paste")
			(net "M_G_DQS_DP<8>")
		)
		(pad "AF69" smd circle
			(at 22.656038 -14.520926)
			(size 0.4318 0.4318)
			(layers "F.Cu" "F.Mask" "F.Paste")
			(net "M_G_ECC<5>")
		)
		(pad "AF71" smd circle
			(at 24.373078 -14.520926)
			(size 0.4318 0.4318)
			(layers "F.Cu" "F.Mask" "F.Paste")
			(net "TP_CPU1_RSVD_241")
		)
		(pad "AF73" smd circle
			(at 26.090118 -14.520926)
			(size 0.4318 0.4318)
			(layers "F.Cu" "F.Mask" "F.Paste")
			(net "GND")
		)
		(pad "AF75" smd circle
			(at 27.806904 -14.520926)
			(size 0.4318 0.4318)
			(layers "F.Cu" "F.Mask" "F.Paste")
			(net "M_J_DQ<12>")
		)
		(pad "AF77" smd circle
			(at 29.523944 -14.520926)
			(size 0.4318 0.4318)
			(layers "F.Cu" "F.Mask" "F.Paste")
			(net "GND")
		)
		(pad "AF79" smd circle
			(at 31.240984 -14.520926)
			(size 0.4318 0.4318)
			(layers "F.Cu" "F.Mask" "F.Paste")
			(net "M_H_DQ<9>")
		)
		(pad "AF81" smd circle
			(at 32.958024 -14.520926)
			(size 0.4318 0.4318)
			(layers "F.Cu" "F.Mask" "F.Paste")
			(net "M_H_DQS_DP<10>")
		)
		(pad "AF83" smd circle
			(at 34.675064 -14.520926)
			(size 0.4318 0.4318)
			(layers "F.Cu" "F.Mask" "F.Paste")
			(net "GND")
		)
		(pad "AF85" smd circle
			(at 36.392104 -14.520926)
			(size 0.4318 0.4318)
			(layers "F.Cu" "F.Mask" "F.Paste")
			(net "GND")
		)
		(pad "AG2" smd circle
			(at -36.392104 -12.225274)
			(size 0.4318 0.4318)
			(layers "F.Cu" "F.Mask" "F.Paste")
			(net "UPI_CPU1_CPU0_P0P0_DP<7>")
		)
		(pad "AG4" smd circle
			(at -34.675064 -12.225274)
			(size 0.4318 0.4318)
			(layers "F.Cu" "F.Mask" "F.Paste")
			(net "UPI_CPU1_CPU0_P0P0_DN<6>")
		)
		(pad "AG6" smd circle
			(at -32.958024 -12.225274)
			(size 0.4318 0.4318)
			(layers "F.Cu" "F.Mask" "F.Paste")
			(net "UPI_CPU0_CPU1_P0P0_DN<4>")
		)
		(pad "AG8" smd circle
			(at -31.240984 -12.225274)
			(size 0.4318 0.4318)
			(layers "F.Cu" "F.Mask" "F.Paste")
			(net "UPI_CPU0_CPU1_P0P0_DP<5>")
		)
		(pad "AG10" smd circle
			(at -29.523944 -12.225274)
			(size 0.4318 0.4318)
			(layers "F.Cu" "F.Mask" "F.Paste")
			(net "TP_XDP_CPU1_OBSDATA_B0_MBP2_N")
		)
		(pad "AG12" smd circle
			(at -27.806904 -12.225274)
			(size 0.4318 0.4318)
			(layers "F.Cu" "F.Mask" "F.Paste")
			(net "GND")
		)
		(pad "AG14" smd circle
			(at -26.090118 -12.225274)
			(size 0.4318 0.4318)
			(layers "F.Cu" "F.Mask" "F.Paste")
			(net "GND")
		)
		(pad "AG16" smd circle
			(at -24.373078 -12.225274)
			(size 0.4318 0.4318)
			(layers "F.Cu" "F.Mask" "F.Paste")
			(net "XDP_CPU_PRDY_N")
		)
		(pad "AG18" smd circle
			(at -22.656038 -12.225274)
			(size 0.4318 0.4318)
			(layers "F.Cu" "F.Mask" "F.Paste")
			(net "GND")
		)
		(pad "AG20" smd circle
			(at -20.938998 -12.225274)
			(size 0.4318 0.4318)
			(layers "F.Cu" "F.Mask" "F.Paste")
			(net "TP_CPU1_RSVD_240")
		)
		(pad "AG22" smd circle
			(at -19.221958 -12.225274)
			(size 0.4318 0.4318)
			(layers "F.Cu" "F.Mask" "F.Paste")
			(net "M_J_DQ<59>")
		)
		(pad "AG24" smd circle
			(at -17.504918 -12.225274)
			(size 0.4318 0.4318)
			(layers "F.Cu" "F.Mask" "F.Paste")
			(net "M_J_DQS_DP<7>")
		)
		(pad "AG26" smd circle
			(at -15.787878 -12.225274)
			(size 0.4318 0.4318)
			(layers "F.Cu" "F.Mask" "F.Paste")
			(net "M_J_DQ<61>")
		)
		(pad "AG28" smd circle
			(at -14.071092 -12.225274)
			(size 0.4318 0.4318)
			(layers "F.Cu" "F.Mask" "F.Paste")
			(net "M_J_DQ<51>")
		)
		(pad "AG30" smd circle
			(at -12.354052 -12.225274)
			(size 0.4318 0.4318)
			(layers "F.Cu" "F.Mask" "F.Paste")
			(net "M_J_DQS_DP<6>")
		)
		(pad "AG32" smd circle
			(at -10.637012 -12.225274)
			(size 0.4318 0.4318)
			(layers "F.Cu" "F.Mask" "F.Paste")
			(net "M_J_DQ<53>")
		)
		(pad "AG34" smd circle
			(at -8.919972 -12.225274)
			(size 0.4318 0.4318)
			(layers "F.Cu" "F.Mask" "F.Paste")
			(net "PVCCIO_CPU1")
		)
		(pad "AG36" smd circle
			(at -7.202932 -12.225274)
			(size 0.4318 0.4318)
			(layers "F.Cu" "F.Mask" "F.Paste")
			(net "GND")
		)
		(pad "AG38" smd circle
			(at -5.485892 -12.225274)
			(size 0.4318 0.4318)
			(layers "F.Cu" "F.Mask" "F.Paste")
			(net "PVCCIN_CPU1")
		)
		(pad "AG40" smd circle
			(at -3.769106 -12.225274)
			(size 0.4318 0.4318)
			(layers "F.Cu" "F.Mask" "F.Paste")
			(net "PVCCIN_CPU1")
		)
		(pad "AG42" smd circle
			(at -2.052066 -12.225274)
			(size 0.4318 0.4318)
			(layers "F.Cu" "F.Mask" "F.Paste")
			(net "PVCCIN_CPU1")
		)
		(pad "AG46" smd circle
			(at 2.910586 -14.025372)
			(size 0.4318 0.4318)
			(layers "F.Cu" "F.Mask" "F.Paste")
			(net "PD_CPU1_RSVD_TEST_2")
		)
		(pad "AG48" smd circle
			(at 4.627626 -14.025372)
			(size 0.4318 0.4318)
			(layers "F.Cu" "F.Mask" "F.Paste")
			(net "TP_CPU1_RSVD_239")
		)
		(pad "AG50" smd circle
			(at 6.344412 -14.025372)
			(size 0.4318 0.4318)
			(layers "F.Cu" "F.Mask" "F.Paste")
			(net "TP_CPU1_RSVD_238")
		)
		(pad "AG52" smd circle
			(at 8.061452 -14.025372)
			(size 0.4318 0.4318)
			(layers "F.Cu" "F.Mask" "F.Paste")
			(net "TP_CPU1_RSVD_237")
		)
		(pad "AG54" smd circle
			(at 9.778492 -14.025372)
			(size 0.4318 0.4318)
			(layers "F.Cu" "F.Mask" "F.Paste")
			(net "TP_CPU1_RSVD_236")
		)
		(pad "AG56" smd circle
			(at 11.495532 -14.025372)
			(size 0.4318 0.4318)
			(layers "F.Cu" "F.Mask" "F.Paste")
			(net "TP_CPU1_RSVD_235")
		)
		(pad "AG58" smd circle
			(at 13.212572 -14.025372)
			(size 0.4318 0.4318)
			(layers "F.Cu" "F.Mask" "F.Paste")
			(net "M_J_MA<9>")
		)
		(pad "AG60" smd circle
			(at 14.929612 -14.025372)
			(size 0.4318 0.4318)
			(layers "F.Cu" "F.Mask" "F.Paste")
			(net "M_J_MA<11>")
		)
		(pad "AG62" smd circle
			(at 16.646398 -14.025372)
			(size 0.4318 0.4318)
			(layers "F.Cu" "F.Mask" "F.Paste")
			(net "M_J_MA<12>")
		)
	)
)
